(kicad_pcb
	(version 20260206)
	(generator "pcbnew")
	(generator_version "10.0")
	(general
		(thickness 1.6)
		(legacy_teardrops no)
	)
	(paper "A4")
	(title_block
		(title "04192023_DAF0TMB3IC0_F0TG_MB_C_brd_V02_OCP.brd")
		(comment 1 "Grand Teton / footprints 1483-1489 of 8354")
	)
	(layers
		(0 "F.Cu" signal "TOP")
		(4 "In1.Cu" signal "GND")
		(6 "In2.Cu" signal "IN1")
		(8 "In3.Cu" signal "GND1")
		(10 "In4.Cu" signal "IN2")
		(12 "In5.Cu" signal "GND2")
		(14 "In6.Cu" signal "IN3")
		(16 "In7.Cu" signal "GND3")
		(18 "In8.Cu" signal "VCC")
		(20 "In9.Cu" signal "VCC1")
		(22 "In10.Cu" signal "GND4")
		(24 "In11.Cu" signal "IN4")
		(26 "In12.Cu" signal "GND5")
		(28 "In13.Cu" signal "IN5")
		(30 "In14.Cu" signal "GND6")
		(32 "In15.Cu" signal "IN6")
		(34 "In16.Cu" signal "GND7")
		(2 "B.Cu" signal "BOTTOM")
		(9 "F.Adhes" user "F.Adhesive")
		(11 "B.Adhes" user "B.Adhesive")
		(13 "F.Paste" user "Package Geometry/Pastemask Top")
		(15 "B.Paste" user "Package Geometry/Pastemask Bottom")
		(5 "F.SilkS" user "Ref Des/Silkscreen Top")
		(7 "B.SilkS" user "Ref Des/Silkscreen Bottom")
		(1 "F.Mask" user "Board Geometry/Soldermask Top")
		(3 "B.Mask" user "Board Geometry/Soldermask Bottom")
		(17 "Dwgs.User" user "User.Drawings")
		(19 "Cmts.User" user "User.Comments")
		(21 "Eco1.User" user "User.Eco1")
		(23 "Eco2.User" user "User.Eco2")
		(25 "Edge.Cuts" user "Board Geometry/Outline")
		(27 "Margin" user)
		(31 "F.CrtYd" user "Package Geometry/Place Bound Top")
		(29 "B.CrtYd" user "Package Geometry/Place Bound Bottom")
		(35 "F.Fab" user "Ref Des/Assembly Top")
		(33 "B.Fab" user "Ref Des/Assembly Bottom")
	)
	(footprint ""
		(layer "F.Cu")
		(at 97.230438 -402.391626)
		(property "Reference" "U45"
			(at -0.31623 -3.169158 0)
			(unlocked yes)
			(layer "F.SilkS")
			(effects
				(font
					(size 0.7874 0.5842)
					(thickness 0.1524)
				)
			)
		)
		(property "Value" ""
			(at 0 0 0)
			(layer "F.Fab")
			(effects
				(font
					(size 1.27 1.27)
				)
			)
		)
		(duplicate_pad_numbers_are_jumpers no)
		(fp_line
			(start -1.03378 -1.284478)
			(end 1.03378 -1.284478)
			(stroke
				(width 0.1524)
				(type default)
			)
			(layer "F.SilkS")
		)
		(fp_line
			(start -1.03378 1.284478)
			(end -1.03378 -1.284478)
			(stroke
				(width 0.1524)
				(type default)
			)
			(layer "F.SilkS")
		)
		(fp_line
			(start 1.03378 -1.284478)
			(end 1.03378 1.284478)
			(stroke
				(width 0.1524)
				(type default)
			)
			(layer "F.SilkS")
		)
		(fp_line
			(start 1.03378 1.284478)
			(end -1.03378 1.284478)
			(stroke
				(width 0.1524)
				(type default)
			)
			(layer "F.SilkS")
		)
		(fp_poly
			(pts
				(xy -1.335278 -1.324102) (xy -2.011426 -1.305306) (xy -1.756156 -1.853692)
			)
			(stroke
				(width 0)
				(type default)
			)
			(fill yes)
			(layer "F.SilkS")
		)
		(fp_line
			(start -0.774954 -1.02489)
			(end 0.774954 -1.02489)
			(stroke
				(width 0.1)
				(type default)
			)
			(layer "F.Fab")
		)
		(fp_line
			(start -0.774954 1.02489)
			(end -0.774954 -1.02489)
			(stroke
				(width 0.1)
				(type default)
			)
			(layer "F.Fab")
		)
		(fp_line
			(start 0.774954 -1.02489)
			(end 0.774954 1.02489)
			(stroke
				(width 0.1)
				(type default)
			)
			(layer "F.Fab")
		)
		(fp_line
			(start 0.774954 1.02489)
			(end -0.774954 1.02489)
			(stroke
				(width 0.1)
				(type default)
			)
			(layer "F.Fab")
		)
		(fp_poly
			(pts
				(xy -1.201674 -0.750062) (xy -1.806702 -0.447548) (xy -1.806702 -1.052576)
			)
			(stroke
				(width 0)
				(type default)
			)
			(fill yes)
			(layer "F.Fab")
		)
		(pad "1" smd rect
			(at -0.64008 -0.750062 90)
			(size 0.3048 0.5334)
			(layers "F.Cu" "F.Mask" "F.Paste")
			(net "SMB_RT_CPU1_P0_ROM_MUX_1D_SCL")
		)
		(pad "2" smd rect
			(at -0.64008 -0.249936 90)
			(size 0.254 0.5334)
			(layers "F.Cu" "F.Mask" "F.Paste")
			(net "SMB_RT_CPU1_P0_ROM_MUX_1D_SDA")
		)
		(pad "3" smd rect
			(at -0.64008 0.249936 90)
			(size 0.254 0.5334)
			(layers "F.Cu" "F.Mask" "F.Paste")
			(net "SMB_RT_CPU1_P0_ROM_MUX_2D_SCL")
		)
		(pad "4" smd rect
			(at -0.64008 0.750062 90)
			(size 0.3048 0.5334)
			(layers "F.Cu" "F.Mask" "F.Paste")
			(net "SMB_RT_CPU1_P0_ROM_MUX_2D_SDA")
		)
		(pad "5" smd rect
			(at 0 0.839978)
			(size 0.3302 0.635)
			(layers "F.Cu" "F.Mask" "F.Paste")
			(net "GND")
		)
		(pad "6" smd rect
			(at 0.64008 0.750062 90)
			(size 0.3048 0.5334)
			(layers "F.Cu" "F.Mask" "F.Paste")
			(net "RT_ROM_MUX1_OE_N")
		)
		(pad "7" smd rect
			(at 0.64008 0.249936 90)
			(size 0.254 0.5334)
			(layers "F.Cu" "F.Mask" "F.Paste")
			(net "SMB_RT_CPU1_P0_ROM_R_SDA")
		)
		(pad "8" smd rect
			(at 0.64008 -0.249936 90)
			(size 0.254 0.5334)
			(layers "F.Cu" "F.Mask" "F.Paste")
			(net "SMB_RT_CPU1_P0_ROM_R_SCL")
		)
		(pad "9" smd rect
			(at 0.64008 -0.750062 90)
			(size 0.3048 0.5334)
			(layers "F.Cu" "F.Mask" "F.Paste")
			(net "FM_SMB_RT_ROM_MUX1_SEL")
		)
		(pad "10" smd rect
			(at 0 -0.839978)
			(size 0.3302 0.635)
			(layers "F.Cu" "F.Mask" "F.Paste")
			(net "P3V3_AUX")
		)
	)
	(footprint ""
		(layer "F.Cu")
		(at 259.131308 -137.103104 -90)
		(property "Reference" "C1105"
			(at 0 0 270)
			(layer "F.SilkS")
			(hide yes)
			(effects
				(font
					(size 1.27 1.27)
				)
			)
		)
		(property "Value" ""
			(at 0 0 270)
			(layer "F.Fab")
			(effects
				(font
					(size 1.27 1.27)
				)
			)
		)
		(duplicate_pad_numbers_are_jumpers no)
		(fp_line
			(start -0.7874 0.4064)
			(end -0.7874 -0.4064)
			(stroke
				(width 0.1524)
				(type default)
			)
			(layer "F.SilkS")
		)
		(fp_line
			(start 0.7874 0.4064)
			(end -0.7874 0.4064)
			(stroke
				(width 0.1524)
				(type default)
			)
			(layer "F.SilkS")
		)
		(fp_line
			(start -0.7874 -0.4064)
			(end 0.7874 -0.4064)
			(stroke
				(width 0.1524)
				(type default)
			)
			(layer "F.SilkS")
		)
		(fp_line
			(start 0.7874 -0.4064)
			(end 0.7874 0.4064)
			(stroke
				(width 0.1524)
				(type default)
			)
			(layer "F.SilkS")
		)
		(fp_line
			(start -0.67945 0.3048)
			(end -0.67945 -0.305054)
			(stroke
				(width 0.1)
				(type default)
			)
			(layer "F.Fab")
		)
		(fp_line
			(start -0.12065 0.3048)
			(end -0.67945 0.3048)
			(stroke
				(width 0.1)
				(type default)
			)
			(layer "F.Fab")
		)
		(fp_line
			(start 0.120396 0.3048)
			(end 0.120396 0.2794)
			(stroke
				(width 0.1)
				(type default)
			)
			(layer "F.Fab")
		)
		(fp_line
			(start 0.67945 0.3048)
			(end 0.120396 0.3048)
			(stroke
				(width 0.1)
				(type default)
			)
			(layer "F.Fab")
		)
		(fp_line
			(start -0.12065 0.2794)
			(end -0.12065 0.3048)
			(stroke
				(width 0.1)
				(type default)
			)
			(layer "F.Fab")
		)
		(fp_line
			(start 0.120396 0.2794)
			(end -0.12065 0.2794)
			(stroke
				(width 0.1)
				(type default)
			)
			(layer "F.Fab")
		)
		(fp_line
			(start -0.12065 -0.2794)
			(end 0.12065 -0.2794)
			(stroke
				(width 0.1)
				(type default)
			)
			(layer "F.Fab")
		)
		(fp_line
			(start 0.12065 -0.2794)
			(end 0.12065 -0.3048)
			(stroke
				(width 0.1)
				(type default)
			)
			(layer "F.Fab")
		)
		(fp_line
			(start 0.12065 -0.3048)
			(end 0.67945 -0.3048)
			(stroke
				(width 0.1)
				(type default)
			)
			(layer "F.Fab")
		)
		(fp_line
			(start 0.67945 -0.3048)
			(end 0.67945 0.3048)
			(stroke
				(width 0.1)
				(type default)
			)
			(layer "F.Fab")
		)
		(fp_line
			(start -0.67945 -0.305054)
			(end -0.12065 -0.305054)
			(stroke
				(width 0.1)
				(type default)
			)
			(layer "F.Fab")
		)
		(fp_line
			(start -0.12065 -0.305054)
			(end -0.12065 -0.2794)
			(stroke
				(width 0.1)
				(type default)
			)
			(layer "F.Fab")
		)
		(pad "1" smd circle
			(at -0.40005 0 270)
			(size 0 0)
			(layers "F.Cu" "F.Mask" "F.Paste")
			(net "P3V3_AUX")
		)
		(pad "2" smd circle
			(at 0.40005 0 270)
			(size 0 0)
			(layers "F.Cu" "F.Mask" "F.Paste")
			(net "GND")
		)
	)
	(footprint ""
		(layer "F.Cu")
		(at 166.929308 -349.265494)
		(property "Reference" "PC638"
			(at 0 0 0)
			(layer "F.SilkS")
			(hide yes)
			(effects
				(font
					(size 1.27 1.27)
				)
			)
		)
		(property "Value" ""
			(at 0 0 0)
			(layer "F.Fab")
			(effects
				(font
					(size 1.27 1.27)
				)
			)
		)
		(duplicate_pad_numbers_are_jumpers no)
		(fp_line
			(start -0.7874 -0.4064)
			(end 0.7874 -0.4064)
			(stroke
				(width 0.1524)
				(type default)
			)
			(layer "F.SilkS")
		)
		(fp_line
			(start -0.7874 0.4064)
			(end -0.7874 -0.4064)
			(stroke
				(width 0.1524)
				(type default)
			)
			(layer "F.SilkS")
		)
		(fp_line
			(start 0.7874 -0.4064)
			(end 0.7874 0.4064)
			(stroke
				(width 0.1524)
				(type default)
			)
			(layer "F.SilkS")
		)
		(fp_line
			(start 0.7874 0.4064)
			(end -0.7874 0.4064)
			(stroke
				(width 0.1524)
				(type default)
			)
			(layer "F.SilkS")
		)
		(fp_line
			(start -0.67945 -0.305054)
			(end -0.12065 -0.305054)
			(stroke
				(width 0.1)
				(type default)
			)
			(layer "F.Fab")
		)
		(fp_line
			(start -0.67945 0.3048)
			(end -0.67945 -0.305054)
			(stroke
				(width 0.1)
				(type default)
			)
			(layer "F.Fab")
		)
		(fp_line
			(start -0.12065 -0.305054)
			(end -0.12065 -0.2794)
			(stroke
				(width 0.1)
				(type default)
			)
			(layer "F.Fab")
		)
		(fp_line
			(start -0.12065 -0.2794)
			(end 0.12065 -0.2794)
			(stroke
				(width 0.1)
				(type default)
			)
			(layer "F.Fab")
		)
		(fp_line
			(start -0.12065 0.2794)
			(end -0.12065 0.3048)
			(stroke
				(width 0.1)
				(type default)
			)
			(layer "F.Fab")
		)
		(fp_line
			(start -0.12065 0.3048)
			(end -0.67945 0.3048)
			(stroke
				(width 0.1)
				(type default)
			)
			(layer "F.Fab")
		)
		(fp_line
			(start 0.120396 0.2794)
			(end -0.12065 0.2794)
			(stroke
				(width 0.1)
				(type default)
			)
			(layer "F.Fab")
		)
		(fp_line
			(start 0.120396 0.3048)
			(end 0.120396 0.2794)
			(stroke
				(width 0.1)
				(type default)
			)
			(layer "F.Fab")
		)
		(fp_line
			(start 0.12065 -0.3048)
			(end 0.67945 -0.3048)
			(stroke
				(width 0.1)
				(type default)
			)
			(layer "F.Fab")
		)
		(fp_line
			(start 0.12065 -0.2794)
			(end 0.12065 -0.3048)
			(stroke
				(width 0.1)
				(type default)
			)
			(layer "F.Fab")
		)
		(fp_line
			(start 0.67945 -0.3048)
			(end 0.67945 0.3048)
			(stroke
				(width 0.1)
				(type default)
			)
			(layer "F.Fab")
		)
		(fp_line
			(start 0.67945 0.3048)
			(end 0.120396 0.3048)
			(stroke
				(width 0.1)
				(type default)
			)
			(layer "F.Fab")
		)
		(pad "1" smd circle
			(at -0.40005 0)
			(size 0 0)
			(layers "F.Cu" "F.Mask" "F.Paste")
			(net "PVDD11_S3_P1_VMON")
		)
		(pad "2" smd circle
			(at 0.40005 0)
			(size 0 0)
			(layers "F.Cu" "F.Mask" "F.Paste")
			(net "GND")
		)
	)
	(footprint ""
		(layer "F.Cu")
		(at 316.021466 -416.899344 -90)
		(property "Reference" "C6510"
			(at 0 0 270)
			(layer "F.SilkS")
			(hide yes)
			(effects
				(font
					(size 1.27 1.27)
				)
			)
		)
		(property "Value" ""
			(at 0 0 270)
			(layer "F.Fab")
			(effects
				(font
					(size 1.27 1.27)
				)
			)
		)
		(duplicate_pad_numbers_are_jumpers no)
		(fp_line
			(start -0.299974 0.150114)
			(end -0.299974 -0.150114)
			(stroke
				(width 0.1)
				(type default)
			)
			(layer "F.Fab")
		)
		(fp_line
			(start 0.299974 0.150114)
			(end -0.299974 0.150114)
			(stroke
				(width 0.1)
				(type default)
			)
			(layer "F.Fab")
		)
		(fp_line
			(start -0.299974 -0.150114)
			(end 0.299974 -0.150114)
			(stroke
				(width 0.1)
				(type default)
			)
			(layer "F.Fab")
		)
		(fp_line
			(start 0.299974 -0.150114)
			(end 0.299974 0.150114)
			(stroke
				(width 0.1)
				(type default)
			)
			(layer "F.Fab")
		)
		(pad "1" smd rect
			(at -0.2667 0 270)
			(size 0.3048 0.381)
			(layers "F.Cu" "F.Mask" "F.Paste")
			(net "P5E_CPU0_P0_TX_BUF_C_DN<4>")
		)
		(pad "2" smd rect
			(at 0.2667 0 270)
			(size 0.3048 0.381)
			(layers "F.Cu" "F.Mask" "F.Paste")
			(net "P5E_CPU0_P0_TX_BUF_DN<4>")
		)
	)
	(footprint ""
		(layer "F.Cu")
		(at 454.847452 -21.302218 90)
		(property "Reference" "R3799"
			(at 0 0 90)
			(layer "F.SilkS")
			(hide yes)
			(effects
				(font
					(size 1.27 1.27)
				)
			)
		)
		(property "Value" ""
			(at 0 0 90)
			(layer "F.Fab")
			(effects
				(font
					(size 1.27 1.27)
				)
			)
		)
		(duplicate_pad_numbers_are_jumpers no)
		(fp_line
			(start 0.7874 -0.4064)
			(end 0.7874 0.4064)
			(stroke
				(width 0.1524)
				(type default)
			)
			(layer "F.SilkS")
		)
		(fp_line
			(start -0.7874 -0.4064)
			(end 0.7874 -0.4064)
			(stroke
				(width 0.1524)
				(type default)
			)
			(layer "F.SilkS")
		)
		(fp_line
			(start 0.7874 0.4064)
			(end -0.7874 0.4064)
			(stroke
				(width 0.1524)
				(type default)
			)
			(layer "F.SilkS")
		)
		(fp_line
			(start -0.7874 0.4064)
			(end -0.7874 -0.4064)
			(stroke
				(width 0.1524)
				(type default)
			)
			(layer "F.SilkS")
		)
		(fp_line
			(start -0.12065 -0.305054)
			(end -0.12065 -0.2794)
			(stroke
				(width 0.1)
				(type default)
			)
			(layer "F.Fab")
		)
		(fp_line
			(start -0.67945 -0.305054)
			(end -0.12065 -0.305054)
			(stroke
				(width 0.1)
				(type default)
			)
			(layer "F.Fab")
		)
		(fp_line
			(start 0.67945 -0.3048)
			(end 0.67945 0.3048)
			(stroke
				(width 0.1)
				(type default)
			)
			(layer "F.Fab")
		)
		(fp_line
			(start 0.12065 -0.3048)
			(end 0.67945 -0.3048)
			(stroke
				(width 0.1)
				(type default)
			)
			(layer "F.Fab")
		)
		(fp_line
			(start 0.12065 -0.2794)
			(end 0.12065 -0.3048)
			(stroke
				(width 0.1)
				(type default)
			)
			(layer "F.Fab")
		)
		(fp_line
			(start -0.12065 -0.2794)
			(end 0.12065 -0.2794)
			(stroke
				(width 0.1)
				(type default)
			)
			(layer "F.Fab")
		)
		(fp_line
			(start 0.120396 0.2794)
			(end -0.12065 0.2794)
			(stroke
				(width 0.1)
				(type default)
			)
			(layer "F.Fab")
		)
		(fp_line
			(start -0.12065 0.2794)
			(end -0.12065 0.3048)
			(stroke
				(width 0.1)
				(type default)
			)
			(layer "F.Fab")
		)
		(fp_line
			(start 0.67945 0.3048)
			(end 0.120396 0.3048)
			(stroke
				(width 0.1)
				(type default)
			)
			(layer "F.Fab")
		)
		(fp_line
			(start 0.120396 0.3048)
			(end 0.120396 0.2794)
			(stroke
				(width 0.1)
				(type default)
			)
			(layer "F.Fab")
		)
		(fp_line
			(start -0.12065 0.3048)
			(end -0.67945 0.3048)
			(stroke
				(width 0.1)
				(type default)
			)
			(layer "F.Fab")
		)
		(fp_line
			(start -0.67945 0.3048)
			(end -0.67945 -0.305054)
			(stroke
				(width 0.1)
				(type default)
			)
			(layer "F.Fab")
		)
		(pad "1" smd circle
			(at -0.40005 0 90)
			(size 0 0)
			(layers "F.Cu" "F.Mask" "F.Paste")
			(net "P3V3_AUX")
		)
		(pad "2" smd circle
			(at 0.40005 0 90)
			(size 0 0)
			(layers "F.Cu" "F.Mask" "F.Paste")
			(net "P12V_OCP_FAULT_1")
		)
	)
	(footprint ""
		(layer "F.Cu")
		(at 164.128704 -51.81473 -90)
		(property "Reference" "C1921"
			(at 0 0 270)
			(layer "F.SilkS")
			(hide yes)
			(effects
				(font
					(size 1.27 1.27)
				)
			)
		)
		(property "Value" ""
			(at 0 0 270)
			(layer "F.Fab")
			(effects
				(font
					(size 1.27 1.27)
				)
			)
		)
		(duplicate_pad_numbers_are_jumpers no)
		(fp_line
			(start -1.2954 0.5842)
			(end -1.2954 -0.5842)
			(stroke
				(width 0.1524)
				(type default)
			)
			(layer "F.SilkS")
		)
		(fp_line
			(start 1.2954 0.5842)
			(end -1.2954 0.5842)
			(stroke
				(width 0.1524)
				(type default)
			)
			(layer "F.SilkS")
		)
		(fp_line
			(start -1.2954 -0.5842)
			(end 1.2954 -0.5842)
			(stroke
				(width 0.1524)
				(type default)
			)
			(layer "F.SilkS")
		)
		(fp_line
			(start 1.2954 -0.5842)
			(end 1.2954 0.5842)
			(stroke
				(width 0.1524)
				(type default)
			)
			(layer "F.SilkS")
		)
		(fp_line
			(start -0.8636 0.4572)
			(end -0.8636 0.4064)
			(stroke
				(width 0.1)
				(type default)
			)
			(layer "F.Fab")
		)
		(fp_line
			(start 0.8636 0.4572)
			(end -0.8636 0.4572)
			(stroke
				(width 0.1)
				(type default)
			)
			(layer "F.Fab")
		)
		(fp_line
			(start -1.1938 0.4064)
			(end -1.1938 -0.4064)
			(stroke
				(width 0.1)
				(type default)
			)
			(layer "F.Fab")
		)
		(fp_line
			(start -0.8636 0.4064)
			(end -1.1938 0.4064)
			(stroke
				(width 0.1)
				(type default)
			)
			(layer "F.Fab")
		)
		(fp_line
			(start 0.8636 0.4064)
			(end 0.8636 0.4572)
			(stroke
				(width 0.1)
				(type default)
			)
			(layer "F.Fab")
		)
		(fp_line
			(start 1.1938 0.4064)
			(end 0.8636 0.4064)
			(stroke
				(width 0.1)
				(type default)
			)
			(layer "F.Fab")
		)
		(fp_line
			(start -1.1938 -0.4064)
			(end -0.8636 -0.4064)
			(stroke
				(width 0.1)
				(type default)
			)
			(layer "F.Fab")
		)
		(fp_line
			(start -0.8636 -0.4064)
			(end -0.8636 -0.4572)
			(stroke
				(width 0.1)
				(type default)
			)
			(layer "F.Fab")
		)
		(fp_line
			(start 0.8636 -0.4064)
			(end 1.1938 -0.4064)
			(stroke
				(width 0.1)
				(type default)
			)
			(layer "F.Fab")
		)
		(fp_line
			(start 1.1938 -0.4064)
			(end 1.1938 0.4064)
			(stroke
				(width 0.1)
				(type default)
			)
			(layer "F.Fab")
		)
		(fp_line
			(start -0.8636 -0.4572)
			(end 0.8636 -0.4572)
			(stroke
				(width 0.1)
				(type default)
			)
			(layer "F.Fab")
		)
		(fp_line
			(start 0.8636 -0.4572)
			(end 0.8636 -0.4064)
			(stroke
				(width 0.1)
				(type default)
			)
			(layer "F.Fab")
		)
		(pad "1" smd rect
			(at -0.7366 0 180)
			(size 0.7112 0.8128)
			(layers "F.Cu" "F.Mask" "F.Paste")
			(net "P3V3_M2_0")
		)
		(pad "2" smd rect
			(at 0.7366 0 180)
			(size 0.7112 0.8128)
			(layers "F.Cu" "F.Mask" "F.Paste")
			(net "GND")
		)
	)
	(footprint ""
		(layer "F.Cu")
		(at 44.21378 -125.24486 -90)
		(property "Reference" "R1481"
			(at -0.3302 2.79781 90)
			(unlocked yes)
			(layer "F.SilkS")
			(effects
				(font
					(size 0.7874 0.5842)
					(thickness 0.1524)
				)
				(justify left)
			)
		)
		(property "Value" ""
			(at 0 0 270)
			(layer "F.Fab")
			(effects
				(font
					(size 1.27 1.27)
				)
			)
		)
		(duplicate_pad_numbers_are_jumpers no)
		(fp_line
			(start -4.18973 1.700022)
			(end 4.18973 1.700022)
			(stroke
				(width 0.1524)
				(type default)
			)
			(layer "F.SilkS")
		)
		(fp_line
			(start 4.18973 1.700022)
			(end 4.18973 -1.700022)
			(stroke
				(width 0.1524)
				(type default)
			)
			(layer "F.SilkS")
		)
		(fp_line
			(start -4.18973 -1.700022)
			(end -4.18973 1.700022)
			(stroke
				(width 0.1524)
				(type default)
			)
			(layer "F.SilkS")
		)
		(fp_line
			(start 4.18973 -1.700022)
			(end -4.18973 -1.700022)
			(stroke
				(width 0.1524)
				(type default)
			)
			(layer "F.SilkS")
		)
		(fp_line
			(start -3.24993 1.700022)
			(end 3.24993 1.700022)
			(stroke
				(width 0.1)
				(type default)
			)
			(layer "F.Fab")
		)
		(fp_line
			(start 3.24993 1.700022)
			(end 3.24993 -1.700022)
			(stroke
				(width 0.1)
				(type default)
			)
			(layer "F.Fab")
		)
		(fp_line
			(start -3.24993 -1.700022)
			(end -3.24993 1.700022)
			(stroke
				(width 0.1)
				(type default)
			)
			(layer "F.Fab")
		)
		(fp_line
			(start 3.24993 -1.700022)
			(end -3.24993 -1.700022)
			(stroke
				(width 0.1)
				(type default)
			)
			(layer "F.Fab")
		)
		(pad "1" smd rect
			(at -2.975102 0 270)
			(size 2.159 2.921)
			(layers "F.Cu" "F.Mask" "F.Paste")
			(net "P3V3_AUX")
		)
		(pad "2" smd rect
			(at 2.975102 0 270)
			(size 2.159 2.921)
			(layers "F.Cu" "F.Mask" "F.Paste")
			(net "P3V3_AUX_DSC")
		)
	)
)
